# BASEBOARD_FAB2 (Tioga Pass) — schematic netlist excerpt (pin names and nets, part order shuffled) for the footprints in the layout excerpt that follows; sources: Cadence DE-HDL packaged netlist, KiCad conversion of Wiwynn_Tioga_Pass_MB.brd

RT45  1R3F-GP  1%  pkg RCL_GP  page 236 : \1\ = VR_P1V05_PCH_STBY_PH1_SW_RC ; \2\ = GND
C3C2  CAP_A  1.0UF 6.3V 10% X6S  pkg 0402V  page 193 : A = PVCCIOMCP_CPU1 ; B = GND
VR1D1  ZENER  13V IC  pkg SM  page 199 : C = P12V_PSU ; A = GND

(kicad_pcb
	(version 20260206)
	(generator "pcbnew")
	(generator_version "10.0")
	(general
		(thickness 1.6)
		(legacy_teardrops no)
	)
	(paper "A4")
	(title_block
		(title "Wiwynn_Tioga_Pass_MB.brd")
		(comment 1 "Tioga Pass / footprints 120-122 of 4770")
	)
	(layers
		(0 "F.Cu" signal "TOP")
		(4 "In1.Cu" signal "L2GND")
		(6 "In2.Cu" signal "L3")
		(8 "In3.Cu" signal "L4GND")
		(10 "In4.Cu" signal "L5")
		(12 "In5.Cu" signal "L6GND")
		(14 "In6.Cu" signal "L7VCC")
		(16 "In7.Cu" signal "L8VCC")
		(18 "In8.Cu" signal "L9GND")
		(20 "In9.Cu" signal "L10")
		(22 "In10.Cu" signal "L11GND")
		(24 "In11.Cu" signal "L12")
		(26 "In12.Cu" signal "L13GND")
		(2 "B.Cu" signal "BOTTOM")
		(9 "F.Adhes" user "F.Adhesive")
		(11 "B.Adhes" user "B.Adhesive")
		(13 "F.Paste" user "Package Geometry/Pastemask Top")
		(15 "B.Paste" user "Package Geometry/Pastemask Bottom")
		(5 "F.SilkS" user "Ref Des/Silkscreen Top")
		(7 "B.SilkS" user "Ref Des/Silkscreen Bottom")
		(1 "F.Mask" user "Board Geometry/Soldermask Top")
		(3 "B.Mask" user "Board Geometry/Soldermask Bottom")
		(17 "Dwgs.User" user "User.Drawings")
		(19 "Cmts.User" user "User.Comments")
		(21 "Eco1.User" user "User.Eco1")
		(23 "Eco2.User" user "User.Eco2")
		(25 "Edge.Cuts" user "Board Geometry/Outline")
		(27 "Margin" user)
		(31 "F.CrtYd" user "Package Geometry/Place Bound Top")
		(29 "B.CrtYd" user "Package Geometry/Place Bound Bottom")
		(35 "F.Fab" user "Ref Des/Assembly Top")
		(33 "B.Fab" user "Ref Des/Assembly Bottom")
	)
	(footprint ""
		(layer "F.Cu")
		(at 3.4798 -64.77 -90)
		(property "Reference" "VR1D1"
			(at -4.06273 5.6896 0)
			(unlocked yes)
			(layer "F.SilkS")
			(effects
				(font
					(size 0.7874 0.5842)
					(thickness 0.1524)
				)
				(justify left)
			)
		)
		(property "Value" ""
			(at 0 0 270)
			(layer "F.Fab")
			(effects
				(font
					(size 1.27 1.27)
				)
			)
		)
		(duplicate_pad_numbers_are_jumpers no)
		(fp_line
			(start -3.1115 7.5946)
			(end -1.9431 7.5946)
			(stroke
				(width 0.1524)
				(type default)
			)
			(layer "F.SilkS")
		)
		(fp_line
			(start -3.1115 7.5946)
			(end -3.1115 -0.2286)
			(stroke
				(width 0.1524)
				(type default)
			)
			(layer "F.SilkS")
		)
		(fp_line
			(start 1.9431 7.5946)
			(end 3.1115 7.5946)
			(stroke
				(width 0.1524)
				(type default)
			)
			(layer "F.SilkS")
		)
		(fp_line
			(start -3.1115 -0.2286)
			(end -1.9431 -0.2286)
			(stroke
				(width 0.1524)
				(type default)
			)
			(layer "F.SilkS")
		)
		(fp_line
			(start 1.9431 -0.2286)
			(end 3.1115 -0.2286)
			(stroke
				(width 0.1524)
				(type default)
			)
			(layer "F.SilkS")
		)
		(fp_line
			(start 3.1115 -0.2286)
			(end 3.1115 7.5946)
			(stroke
				(width 0.1524)
				(type default)
			)
			(layer "F.SilkS")
		)
		(fp_circle
			(center -2.065528 -0.818388)
			(end -2.065528 -0.945388)
			(stroke
				(width 0.254)
				(type default)
			)
			(fill no)
			(layer "F.SilkS")
		)
		(fp_poly
			(pts
				(xy -3.1115 7.5946) (xy 3.1115 7.5946) (xy 3.1115 -0.2286) (xy -3.1115 -0.2286)
			)
			(stroke
				(width 0)
				(type default)
			)
			(fill no)
			(layer "F.CrtYd")
		)
		(fp_line
			(start -3.1115 7.5946)
			(end 3.1115 7.5946)
			(stroke
				(width 0.1)
				(type default)
			)
			(layer "F.Fab")
		)
		(fp_line
			(start 3.1115 7.5946)
			(end 3.1115 -0.2286)
			(stroke
				(width 0.1)
				(type default)
			)
			(layer "F.Fab")
		)
		(fp_line
			(start -3.1115 -0.2286)
			(end -3.1115 7.5946)
			(stroke
				(width 0.1)
				(type default)
			)
			(layer "F.Fab")
		)
		(fp_line
			(start 3.1115 -0.2286)
			(end -3.1115 -0.2286)
			(stroke
				(width 0.1)
				(type default)
			)
			(layer "F.Fab")
		)
		(fp_circle
			(center -2.413 -0.9906)
			(end -2.413 -1.1176)
			(stroke
				(width 0.254)
				(type default)
			)
			(fill no)
			(layer "F.Fab")
		)
		(pad "1" smd rect
			(at 0 0 270)
			(size 3.048 2.286)
			(layers "F.Cu" "F.Mask" "F.Paste")
			(net "P12V_PSU")
		)
		(pad "2" smd rect
			(at 0 7.366 270)
			(size 3.048 2.286)
			(layers "F.Cu" "F.Mask" "F.Paste")
			(net "GND")
		)
	)
	(footprint ""
		(layer "F.Cu")
		(at 381.51562 -150.965916 180)
		(property "Reference" "RT45"
			(at 0 0 180)
			(layer "F.SilkS")
			(hide yes)
			(effects
				(font
					(size 1.27 1.27)
				)
			)
		)
		(property "Value" "*"
			(at -0.0254 -2.6289 180)
			(unlocked yes)
			(layer "F.Fab")
			(hide yes)
			(effects
				(font
					(size 1.27 1.016)
					(thickness 0.1524)
				)
			)
		)
		(property "Device Type" "1R3F-GP_RCL_GP-1R3F-GP,64.1R00A"
			(at -0.0254 -4.1529 180)
			(unlocked yes)
			(layer "F.Fab")
			(hide yes)
			(effects
				(font
					(size 1.27 1.016)
					(thickness 0.1524)
				)
			)
		)
		(duplicate_pad_numbers_are_jumpers no)
		(fp_line
			(start 0.2032 0)
			(end 0.4826 0)
			(stroke
				(width 0.2032)
				(type default)
			)
			(layer "F.SilkS")
		)
		(fp_line
			(start -0.4826 0)
			(end -0.2032 0)
			(stroke
				(width 0.2032)
				(type default)
			)
			(layer "F.SilkS")
		)
		(fp_poly
			(pts
				(xy -0.5842 1.3335) (xy 0.5842 1.3335) (xy 0.5842 -1.3335) (xy -0.5842 -1.3335)
			)
			(stroke
				(width 0)
				(type default)
			)
			(fill no)
			(layer "F.CrtYd")
		)
		(fp_rect
			(start -0.5842 1.3335)
			(end 0.5842 -1.3335)
			(stroke
				(width 0)
				(type default)
			)
			(fill no)
			(layer "F.Fab")
		)
		(pad "1" smd custom
			(at 0 -0.762 180)
			(size 0.2159 0.2159)
			(layers "F.Cu" "F.Mask" "F.Paste")
			(net "VR_P1V05_PCH_STBY_PH1_SW_RC")
			(options
				(clearance outline)
				(anchor circle)
			)
			(primitives
				(gr_poly
					(pts
						(arc
							(start -0.3302 -0.4318)
							(mid -0.402042 -0.402042)
							(end -0.4318 -0.3302)
						)
						(arc
							(start -0.4318 0.3302)
							(mid -0.402042 0.402042)
							(end -0.3302 0.4318)
						)
						(arc
							(start 0.3302 0.4318)
							(mid 0.402042 0.402042)
							(end 0.4318 0.3302)
						)
						(arc
							(start 0.4318 -0.3302)
							(mid 0.402042 -0.402042)
							(end 0.3302 -0.4318)
						)
					)
					(width 0)
					(fill yes)
				)
			)
		)
		(pad "2" smd custom
			(at 0 0.762 180)
			(size 0.2159 0.2159)
			(layers "F.Cu" "F.Mask" "F.Paste")
			(net "GND")
			(options
				(clearance outline)
				(anchor circle)
			)
			(primitives
				(gr_poly
					(pts
						(arc
							(start -0.3302 -0.4318)
							(mid -0.402042 -0.402042)
							(end -0.4318 -0.3302)
						)
						(arc
							(start -0.4318 0.3302)
							(mid -0.402042 0.402042)
							(end -0.3302 0.4318)
						)
						(arc
							(start 0.3302 0.4318)
							(mid 0.402042 0.402042)
							(end 0.4318 0.3302)
						)
						(arc
							(start 0.4318 -0.3302)
							(mid 0.402042 -0.402042)
							(end 0.3302 -0.4318)
						)
					)
					(width 0)
					(fill yes)
				)
			)
		)
	)
	(footprint ""
		(layer "F.Cu")
		(at 162.687 -104.14)
		(property "Reference" "C3C2"
			(at 0 0 0)
			(layer "F.SilkS")
			(hide yes)
			(effects
				(font
					(size 1.27 1.27)
				)
			)
		)
		(property "Value" ""
			(at 0 0 0)
			(layer "F.Fab")
			(effects
				(font
					(size 1.27 1.27)
				)
			)
		)
		(duplicate_pad_numbers_are_jumpers no)
		(fp_poly
			(pts
				(xy 0.3048 -0.1016) (xy 0.3048 0.9906) (xy -0.3048 0.9906) (xy -0.3048 -0.1016)
			)
			(stroke
				(width 0)
				(type default)
			)
			(fill no)
			(layer "F.CrtYd")
		)
		(fp_line
			(start -0.3048 -0.1016)
			(end -0.3048 0.9906)
			(stroke
				(width 0.1)
				(type default)
			)
			(layer "F.Fab")
		)
		(fp_line
			(start -0.3048 0.9906)
			(end 0.3048 0.9906)
			(stroke
				(width 0.1)
				(type default)
			)
			(layer "F.Fab")
		)
		(fp_line
			(start 0.3048 -0.1016)
			(end -0.3048 -0.1016)
			(stroke
				(width 0.1)
				(type default)
			)
			(layer "F.Fab")
		)
		(fp_line
			(start 0.3048 0.9906)
			(end 0.3048 -0.1016)
			(stroke
				(width 0.1)
				(type default)
			)
			(layer "F.Fab")
		)
		(pad "1" smd rect
			(at 0 0)
			(size 0.508 0.508)
			(layers "F.Cu" "F.Mask" "F.Paste")
			(net "PVCCIOMCP_CPU1")
		)
		(pad "2" smd rect
			(at 0 0.889)
			(size 0.508 0.508)
			(layers "F.Cu" "F.Mask" "F.Paste")
			(net "GND")
		)
		(zone
			(layer "F.Cu")
			(hatch none 0.5)
			(connect_pads
				(clearance 0)
			)
			(min_thickness 0.25)
			(keepout
				(tracks allowed)
				(vias not_allowed)
				(pads allowed)
				(copperpour not_allowed)
				(footprints allowed)
			)
			(placement
				(enabled no)
				(sheetname "")
			)
			(fill
				(thermal_gap 0.5)
				(thermal_bridge_width 0.5)
				(island_removal_mode 0)
			)
			(polygon
				(pts
					(xy 162.433 -103.886) (xy 162.941 -103.886) (xy 162.941 -103.505) (xy 162.433 -103.505)
				)
			)
		)
		(zone
			(layer "F.Cu")
			(hatch none 0.5)
			(connect_pads
				(clearance 0)
			)
			(min_thickness 0.25)
			(keepout
				(tracks not_allowed)
				(vias allowed)
				(pads allowed)
				(copperpour not_allowed)
				(footprints allowed)
			)
			(placement
				(enabled no)
				(sheetname "")
			)
			(fill
				(thermal_gap 0.5)
				(thermal_bridge_width 0.5)
				(island_removal_mode 0)
			)
			(polygon
				(pts
					(xy 162.433 -103.505) (xy 162.941 -103.505) (xy 162.941 -103.886) (xy 162.433 -103.886)
				)
			)
		)
	)
)
